# T6G (Grand Teton) — schematic netlist excerpt (pin names and nets, part order shuffled) for the footprints in the layout excerpt that follows; sources: Cadence DE-HDL packaged netlist, KiCad conversion of 04192023_DAF0TMB3IC0_F0TG_MB_C_brd_V02_OCP.brd

U321  74LVC1G66GV  IC  pkg SC74AXA  page 139
  Y  = CLK_50M_NCSI_OCP_V3_2
  Z  = CLK_50M_NCSI_OCP_V3_2_ISO_R
  GND  = GND
  E  = FB_BMC_ISOLATE1
  VCC  = P3V3_AUX

PR3971  Q_RES  9.76K 1% CHIP  pkg 0402LF  page 146 : A = P3V3_E1S_SENSE_0 ; B = GND

(kicad_pcb
	(version 20260206)
	(generator "pcbnew")
	(generator_version "10.0")
	(general
		(thickness 1.6)
		(legacy_teardrops no)
	)
	(paper "A4")
	(title_block
		(title "04192023_DAF0TMB3IC0_F0TG_MB_C_brd_V02_OCP.brd")
		(comment 1 "Grand Teton / footprints 1627-1629 of 8354")
	)
	(layers
		(0 "F.Cu" signal "TOP")
		(4 "In1.Cu" signal "GND")
		(6 "In2.Cu" signal "IN1")
		(8 "In3.Cu" signal "GND1")
		(10 "In4.Cu" signal "IN2")
		(12 "In5.Cu" signal "GND2")
		(14 "In6.Cu" signal "IN3")
		(16 "In7.Cu" signal "GND3")
		(18 "In8.Cu" signal "VCC")
		(20 "In9.Cu" signal "VCC1")
		(22 "In10.Cu" signal "GND4")
		(24 "In11.Cu" signal "IN4")
		(26 "In12.Cu" signal "GND5")
		(28 "In13.Cu" signal "IN5")
		(30 "In14.Cu" signal "GND6")
		(32 "In15.Cu" signal "IN6")
		(34 "In16.Cu" signal "GND7")
		(2 "B.Cu" signal "BOTTOM")
		(9 "F.Adhes" user "F.Adhesive")
		(11 "B.Adhes" user "B.Adhesive")
		(13 "F.Paste" user "Package Geometry/Pastemask Top")
		(15 "B.Paste" user "Package Geometry/Pastemask Bottom")
		(5 "F.SilkS" user "Ref Des/Silkscreen Top")
		(7 "B.SilkS" user "Ref Des/Silkscreen Bottom")
		(1 "F.Mask" user "Board Geometry/Soldermask Top")
		(3 "B.Mask" user "Board Geometry/Soldermask Bottom")
		(17 "Dwgs.User" user "User.Drawings")
		(19 "Cmts.User" user "User.Comments")
		(21 "Eco1.User" user "User.Eco1")
		(23 "Eco2.User" user "User.Eco2")
		(25 "Edge.Cuts" user "Board Geometry/Outline")
		(27 "Margin" user)
		(31 "F.CrtYd" user "Package Geometry/Place Bound Top")
		(29 "B.CrtYd" user "Package Geometry/Place Bound Bottom")
		(35 "F.Fab" user "Ref Des/Assembly Top")
		(33 "B.Fab" user "Ref Des/Assembly Bottom")
	)
	(footprint ""
		(layer "F.Cu")
		(at 89.533984 -32.07131)
		(property "Reference" "U321"
			(at -2.2606 -2.352548 0)
			(unlocked yes)
			(layer "F.SilkS")
			(effects
				(font
					(size 0.7874 0.5842)
					(thickness 0.1524)
				)
				(justify left)
			)
		)
		(property "Value" ""
			(at 0 0 0)
			(layer "F.Fab")
			(effects
				(font
					(size 1.27 1.27)
				)
			)
		)
		(duplicate_pad_numbers_are_jumpers no)
		(fp_line
			(start -2.032 -1.549908)
			(end 2.032 -1.549908)
			(stroke
				(width 0.1524)
				(type default)
			)
			(layer "F.SilkS")
		)
		(fp_line
			(start -2.032 1.549908)
			(end -2.032 -1.549908)
			(stroke
				(width 0.1524)
				(type default)
			)
			(layer "F.SilkS")
		)
		(fp_line
			(start 2.032 -1.549908)
			(end 2.032 1.549908)
			(stroke
				(width 0.1524)
				(type default)
			)
			(layer "F.SilkS")
		)
		(fp_line
			(start 2.032 1.549908)
			(end -2.032 1.549908)
			(stroke
				(width 0.1524)
				(type default)
			)
			(layer "F.SilkS")
		)
		(fp_poly
			(pts
				(xy -2.733548 -2.327656) (xy -2.993644 -1.89103) (xy -2.208784 -1.71958)
			)
			(stroke
				(width 0)
				(type default)
			)
			(fill yes)
			(layer "F.SilkS")
		)
		(fp_line
			(start -0.849884 -1.549908)
			(end -0.849884 1.549908)
			(stroke
				(width 0.1)
				(type default)
			)
			(layer "F.Fab")
		)
		(fp_line
			(start -0.849884 1.549908)
			(end 0.849884 1.549908)
			(stroke
				(width 0.1)
				(type default)
			)
			(layer "F.Fab")
		)
		(fp_line
			(start 0.849884 -1.549908)
			(end -0.849884 -1.549908)
			(stroke
				(width 0.1)
				(type default)
			)
			(layer "F.Fab")
		)
		(fp_line
			(start 0.849884 1.549908)
			(end 0.849884 -1.549908)
			(stroke
				(width 0.1)
				(type default)
			)
			(layer "F.Fab")
		)
		(fp_poly
			(pts
				(xy -2.9464 -1.2192) (xy -2.9464 -0.7112) (xy -2.1844 -0.9652)
			)
			(stroke
				(width 0)
				(type default)
			)
			(fill yes)
			(layer "F.Fab")
		)
		(pad "1" smd rect
			(at -1.225042 -0.94996 270)
			(size 0.4572 1.3208)
			(layers "F.Cu" "F.Mask" "F.Paste")
			(net "CLK_50M_NCSI_OCP_V3_2")
		)
		(pad "2" smd rect
			(at -1.225042 0 270)
			(size 0.4572 1.3208)
			(layers "F.Cu" "F.Mask" "F.Paste")
			(net "CLK_50M_NCSI_OCP_V3_2_ISO_R")
		)
		(pad "3" smd rect
			(at -1.225042 0.94996 270)
			(size 0.4572 1.3208)
			(layers "F.Cu" "F.Mask" "F.Paste")
			(net "GND")
		)
		(pad "4" smd rect
			(at 1.225042 0.94996 270)
			(size 0.4572 1.3208)
			(layers "F.Cu" "F.Mask" "F.Paste")
			(net "FB_BMC_ISOLATE1")
		)
		(pad "5" smd rect
			(at 1.225042 -0.94996 270)
			(size 0.4572 1.3208)
			(layers "F.Cu" "F.Mask" "F.Paste")
			(net "P3V3_AUX")
		)
	)
	(footprint ""
		(layer "F.Cu")
		(at 218.011502 -72.015858 180)
		(property "Reference" "PR3971"
			(at 0 0 180)
			(layer "F.SilkS")
			(hide yes)
			(effects
				(font
					(size 1.27 1.27)
				)
			)
		)
		(property "Value" ""
			(at 0 0 180)
			(layer "F.Fab")
			(effects
				(font
					(size 1.27 1.27)
				)
			)
		)
		(duplicate_pad_numbers_are_jumpers no)
		(fp_line
			(start 0.7874 0.4064)
			(end -0.7874 0.4064)
			(stroke
				(width 0.1524)
				(type default)
			)
			(layer "F.SilkS")
		)
		(fp_line
			(start 0.7874 -0.4064)
			(end 0.7874 0.4064)
			(stroke
				(width 0.1524)
				(type default)
			)
			(layer "F.SilkS")
		)
		(fp_line
			(start -0.7874 0.4064)
			(end -0.7874 -0.4064)
			(stroke
				(width 0.1524)
				(type default)
			)
			(layer "F.SilkS")
		)
		(fp_line
			(start -0.7874 -0.4064)
			(end 0.7874 -0.4064)
			(stroke
				(width 0.1524)
				(type default)
			)
			(layer "F.SilkS")
		)
		(fp_line
			(start 0.67945 0.3048)
			(end 0.120396 0.3048)
			(stroke
				(width 0.1)
				(type default)
			)
			(layer "F.Fab")
		)
		(fp_line
			(start 0.67945 -0.3048)
			(end 0.67945 0.3048)
			(stroke
				(width 0.1)
				(type default)
			)
			(layer "F.Fab")
		)
		(fp_line
			(start 0.12065 -0.2794)
			(end 0.12065 -0.3048)
			(stroke
				(width 0.1)
				(type default)
			)
			(layer "F.Fab")
		)
		(fp_line
			(start 0.12065 -0.3048)
			(end 0.67945 -0.3048)
			(stroke
				(width 0.1)
				(type default)
			)
			(layer "F.Fab")
		)
		(fp_line
			(start 0.120396 0.3048)
			(end 0.120396 0.2794)
			(stroke
				(width 0.1)
				(type default)
			)
			(layer "F.Fab")
		)
		(fp_line
			(start 0.120396 0.2794)
			(end -0.12065 0.2794)
			(stroke
				(width 0.1)
				(type default)
			)
			(layer "F.Fab")
		)
		(fp_line
			(start -0.12065 0.3048)
			(end -0.67945 0.3048)
			(stroke
				(width 0.1)
				(type default)
			)
			(layer "F.Fab")
		)
		(fp_line
			(start -0.12065 0.2794)
			(end -0.12065 0.3048)
			(stroke
				(width 0.1)
				(type default)
			)
			(layer "F.Fab")
		)
		(fp_line
			(start -0.12065 -0.2794)
			(end 0.12065 -0.2794)
			(stroke
				(width 0.1)
				(type default)
			)
			(layer "F.Fab")
		)
		(fp_line
			(start -0.12065 -0.305054)
			(end -0.12065 -0.2794)
			(stroke
				(width 0.1)
				(type default)
			)
			(layer "F.Fab")
		)
		(fp_line
			(start -0.67945 0.3048)
			(end -0.67945 -0.305054)
			(stroke
				(width 0.1)
				(type default)
			)
			(layer "F.Fab")
		)
		(fp_line
			(start -0.67945 -0.305054)
			(end -0.12065 -0.305054)
			(stroke
				(width 0.1)
				(type default)
			)
			(layer "F.Fab")
		)
		(pad "1" smd circle
			(at -0.40005 0 180)
			(size 0 0)
			(layers "F.Cu" "F.Mask" "F.Paste")
			(net "P3V3_E1S_SENSE_0")
		)
		(pad "2" smd circle
			(at 0.40005 0 180)
			(size 0 0)
			(layers "F.Cu" "F.Mask" "F.Paste")
			(net "GND")
		)
	)
	(footprint ""
		(layer "F.Cu")
		(at 48.803306 19.444716 -90)
		(property "Reference" "JP6001_23"
			(at 0 0 270)
			(layer "F.SilkS")
			(hide yes)
			(effects
				(font
					(size 1.27 1.27)
				)
			)
		)
		(property "Value" ""
			(at 0 0 270)
			(layer "F.Fab")
			(effects
				(font
					(size 1.27 1.27)
				)
			)
		)
		(duplicate_pad_numbers_are_jumpers no)
		(pad "1" smd circle
			(at 0 0 270)
			(size 0.762 0.762)
			(layers "F.Cu" "F.Mask" "F.Paste")
			(net "Net_10791")
		)
	)
)
